#ISCELL
  mstr_misc dns *
  *
#ISCELL
  mstr_misc prelim *
  *
#ISCELL
  mstr_symbols cad_note *
  *
#ISCELL
  mstr_symbols intel_corp_bpage *
  *
#CELL
  mstr_vreg mic5166 *
  page221_i1
#ISCELL
  mstr_symbols pvtt_abc *
  page221_i11
#ISCELL
  mstr_symbols gnd *
  page221_i14
#CELL
  mstr_discrete cap *
  page221_i15
#ISCELL
  mstr_symbols gnd *
  page221_i19
#CELL
  mstr_discrete cap *
  page221_i20
#CELL
  mstr_discrete cap *
  page221_i22
#ISCELL
  mstr_symbols gnd *
  page221_i23
#CELL
  mstr_discrete cap *
  page221_i24
#ISCELL
  mstr_symbols gnd *
  page221_i25
#CELL
  mstr_discrete cap *
  page221_i26
#CELL
  mstr_discrete res *
  page221_i28
#ISCELL
  mstr_symbols gnd *
  page221_i29
#ISCELL
  mstr_symbols pvddq_abc *
  page221_i31
#CELL
  mstr_discrete res *
  page221_i32
#CELL
  mstr_discrete cap *
  page221_i34
#ISCELL
  mstr_symbols gnd *
  page221_i35
#ISCELL
  mstr_symbols gnd *
  page221_i36
#CELL
  mstr_discrete res *
  page221_i37
#CELL
  mstr_discrete res *
  page221_i38
#CELL
  mstr_discrete cap *
  page221_i39
#ISCELL
  mstr_symbols gnd *
  page221_i40
#ISCELL
  mstr_standard offpage *
  page221_i41
#ISCELL
  mstr_symbols p3v3 *
  page221_i43
#CELL
  mstr_discrete res *
  page221_i45
#ISCELL
  mstr_symbols p3v3 *
  page221_i46
#ISCELL
  mstr_symbols gnd *
  page221_i48
#CELL
  mstr_discrete cap *
  page221_i49
#CELL
  dev_discrete cap_a *
  page221_i50
#CELL
  dev_discrete cap_a *
  page221_i51
#CELL
  dev_discrete cap_a *
  page221_i52
#CELL
  mstr_discrete res *
  page221_i54
#CELL
  mstr_discrete res *
  page221_i55
#CELL
  mstr_misc shunt *
  page221_i56
#ISCELL
  mstr_standard offpage *
  page221_i6
#ISCELL
  mstr_symbols pvtt_abc *
  page221_i7
#ISCELL
  mstr_symbols gnd *
  page221_i8
